# BASEBOARD_FAB2 (Tioga Pass) — schematic netlist excerpt (pin names and nets, part order shuffled) for the footprints in the layout excerpt that follows; sources: Cadence DE-HDL packaged netlist, KiCad conversion of Wiwynn_Tioga_Pass_MB.brd

R5D2  RES  90.9 1% CHIP  pkg 0402  page 21 : A = A_CPU0_DEF_RCOMP1 ; B = GND
C5G16  CAP_A  47UF 4V 20% X5R  pkg 0603V  page 217 : A = PVDDQ_ABC ; B = GND
RF15  RES  1.0K 0.1% CHIP  pkg 0402  page 215 : A = VR_PVDDQ_ABC_AIREF1 ; B = ISENSE_PVDDQ_ABC_PH1_IMON

(kicad_pcb
	(version 20260206)
	(generator "pcbnew")
	(generator_version "10.0")
	(general
		(thickness 1.6)
		(legacy_teardrops no)
	)
	(paper "A4")
	(title_block
		(title "Wiwynn_Tioga_Pass_MB.brd")
		(comment 1 "Tioga Pass / footprints 1177-1179 of 4770")
	)
	(layers
		(0 "F.Cu" signal "TOP")
		(4 "In1.Cu" signal "L2GND")
		(6 "In2.Cu" signal "L3")
		(8 "In3.Cu" signal "L4GND")
		(10 "In4.Cu" signal "L5")
		(12 "In5.Cu" signal "L6GND")
		(14 "In6.Cu" signal "L7VCC")
		(16 "In7.Cu" signal "L8VCC")
		(18 "In8.Cu" signal "L9GND")
		(20 "In9.Cu" signal "L10")
		(22 "In10.Cu" signal "L11GND")
		(24 "In11.Cu" signal "L12")
		(26 "In12.Cu" signal "L13GND")
		(2 "B.Cu" signal "BOTTOM")
		(9 "F.Adhes" user "F.Adhesive")
		(11 "B.Adhes" user "B.Adhesive")
		(13 "F.Paste" user "Package Geometry/Pastemask Top")
		(15 "B.Paste" user "Package Geometry/Pastemask Bottom")
		(5 "F.SilkS" user "Ref Des/Silkscreen Top")
		(7 "B.SilkS" user "Ref Des/Silkscreen Bottom")
		(1 "F.Mask" user "Board Geometry/Soldermask Top")
		(3 "B.Mask" user "Board Geometry/Soldermask Bottom")
		(17 "Dwgs.User" user "User.Drawings")
		(19 "Cmts.User" user "User.Comments")
		(21 "Eco1.User" user "User.Eco1")
		(23 "Eco2.User" user "User.Eco2")
		(25 "Edge.Cuts" user "Board Geometry/Outline")
		(27 "Margin" user)
		(31 "F.CrtYd" user "Package Geometry/Place Bound Top")
		(29 "B.CrtYd" user "Package Geometry/Place Bound Bottom")
		(35 "F.Fab" user "Ref Des/Assembly Top")
		(33 "B.Fab" user "Ref Des/Assembly Bottom")
	)
	(footprint ""
		(layer "F.Cu")
		(at 276.27072 -83.88604)
		(property "Reference" "R5D2"
			(at 0 0 0)
			(layer "F.SilkS")
			(hide yes)
			(effects
				(font
					(size 1.27 1.27)
				)
			)
		)
		(property "Value" ""
			(at 0 0 0)
			(layer "F.Fab")
			(effects
				(font
					(size 1.27 1.27)
				)
			)
		)
		(duplicate_pad_numbers_are_jumpers no)
		(fp_poly
			(pts
				(xy -0.2794 -0.1016) (xy 0.2794 -0.1016) (xy 0.2794 0.9906) (xy -0.2794 0.9906)
			)
			(stroke
				(width 0)
				(type default)
			)
			(fill no)
			(layer "F.CrtYd")
		)
		(fp_line
			(start -0.2794 -0.1016)
			(end -0.2794 0.9906)
			(stroke
				(width 0.1)
				(type default)
			)
			(layer "F.Fab")
		)
		(fp_line
			(start -0.2794 0.9906)
			(end 0.2794 0.9906)
			(stroke
				(width 0.1)
				(type default)
			)
			(layer "F.Fab")
		)
		(fp_line
			(start 0.2794 -0.1016)
			(end -0.2794 -0.1016)
			(stroke
				(width 0.1)
				(type default)
			)
			(layer "F.Fab")
		)
		(fp_line
			(start 0.2794 0.9906)
			(end 0.2794 -0.1016)
			(stroke
				(width 0.1)
				(type default)
			)
			(layer "F.Fab")
		)
		(pad "1" smd rect
			(at 0 0)
			(size 0.508 0.508)
			(layers "F.Cu" "F.Mask" "F.Paste")
			(net "A_CPU0_DEF_RCOMP1")
		)
		(pad "2" smd rect
			(at 0 0.889)
			(size 0.508 0.508)
			(layers "F.Cu" "F.Mask" "F.Paste")
			(net "GND")
		)
		(zone
			(layer "F.Cu")
			(hatch none 0.5)
			(connect_pads
				(clearance 0)
			)
			(min_thickness 0.25)
			(keepout
				(tracks allowed)
				(vias not_allowed)
				(pads allowed)
				(copperpour not_allowed)
				(footprints allowed)
			)
			(placement
				(enabled no)
				(sheetname "")
			)
			(fill
				(thermal_gap 0.5)
				(thermal_bridge_width 0.5)
				(island_removal_mode 0)
			)
			(polygon
				(pts
					(xy 276.01672 -83.63204) (xy 276.52472 -83.63204) (xy 276.52472 -83.25104) (xy 276.01672 -83.25104)
				)
			)
		)
		(zone
			(layer "F.Cu")
			(hatch none 0.5)
			(connect_pads
				(clearance 0)
			)
			(min_thickness 0.25)
			(keepout
				(tracks not_allowed)
				(vias allowed)
				(pads allowed)
				(copperpour not_allowed)
				(footprints allowed)
			)
			(placement
				(enabled no)
				(sheetname "")
			)
			(fill
				(thermal_gap 0.5)
				(thermal_bridge_width 0.5)
				(island_removal_mode 0)
			)
			(polygon
				(pts
					(xy 276.01672 -83.25104) (xy 276.52472 -83.25104) (xy 276.52472 -83.63204) (xy 276.01672 -83.63204)
				)
			)
		)
	)
	(footprint ""
		(layer "F.Cu")
		(at 269.559532 -3.3528 90)
		(property "Reference" "C5G16"
			(at 1.848866 0.752348 90)
			(unlocked yes)
			(layer "F.SilkS")
			(effects
				(font
					(size 1.27 0.9652)
					(thickness 0.1524)
				)
			)
		)
		(property "Value" ""
			(at 0 0 90)
			(layer "F.Fab")
			(effects
				(font
					(size 1.27 1.27)
				)
			)
		)
		(duplicate_pad_numbers_are_jumpers no)
		(fp_rect
			(start -0.500126 1.598422)
			(end 0.500126 -0.201422)
			(stroke
				(width 0)
				(type default)
			)
			(fill no)
			(layer "F.CrtYd")
		)
		(fp_line
			(start 0.500126 -0.201422)
			(end 0.500126 1.598422)
			(stroke
				(width 0.1)
				(type default)
			)
			(layer "F.Fab")
		)
		(fp_line
			(start -0.500126 -0.201422)
			(end 0.500126 -0.201422)
			(stroke
				(width 0.1)
				(type default)
			)
			(layer "F.Fab")
		)
		(fp_line
			(start 0.500126 1.598422)
			(end -0.500126 1.598422)
			(stroke
				(width 0.1)
				(type default)
			)
			(layer "F.Fab")
		)
		(fp_line
			(start -0.500126 1.598422)
			(end -0.500126 -0.201422)
			(stroke
				(width 0.1)
				(type default)
			)
			(layer "F.Fab")
		)
		(pad "1" smd rect
			(at 0 0)
			(size 0.889 0.9906)
			(layers "F.Cu" "F.Mask" "F.Paste")
			(net "PVDDQ_ABC")
		)
		(pad "2" smd rect
			(at 0 1.397)
			(size 0.889 0.9906)
			(layers "F.Cu" "F.Mask" "F.Paste")
			(net "GND")
		)
		(zone
			(layer "F.Cu")
			(hatch none 0.5)
			(connect_pads
				(clearance 0)
			)
			(min_thickness 0.25)
			(keepout
				(tracks allowed)
				(vias not_allowed)
				(pads allowed)
				(copperpour not_allowed)
				(footprints allowed)
			)
			(placement
				(enabled no)
				(sheetname "")
			)
			(fill
				(thermal_gap 0.5)
				(thermal_bridge_width 0.5)
				(island_removal_mode 0)
			)
			(polygon
				(pts
					(xy 270.512032 -2.8575) (xy 270.512032 -3.8481) (xy 270.004032 -3.8481) (xy 270.004032 -2.8575)
				)
			)
		)
		(zone
			(layer "F.Cu")
			(hatch none 0.5)
			(connect_pads
				(clearance 0)
			)
			(min_thickness 0.25)
			(keepout
				(tracks not_allowed)
				(vias allowed)
				(pads allowed)
				(copperpour not_allowed)
				(footprints allowed)
			)
			(placement
				(enabled no)
				(sheetname "")
			)
			(fill
				(thermal_gap 0.5)
				(thermal_bridge_width 0.5)
				(island_removal_mode 0)
			)
			(polygon
				(pts
					(xy 270.512032 -2.8575) (xy 270.512032 -3.8481) (xy 270.004032 -3.8481) (xy 270.004032 -2.8575)
				)
			)
		)
	)
	(footprint ""
		(layer "F.Cu")
		(at 341.996776 -11.798046 90)
		(property "Reference" "RF15"
			(at -0.8382 -0.67818 90)
			(unlocked yes)
			(layer "F.SilkS")
			(effects
				(font
					(size 0.4064 0.254)
					(thickness 0.1524)
				)
				(justify left)
			)
		)
		(property "Value" ""
			(at 0 0 90)
			(layer "F.Fab")
			(effects
				(font
					(size 1.27 1.27)
				)
			)
		)
		(duplicate_pad_numbers_are_jumpers no)
		(fp_poly
			(pts
				(xy -0.2794 -0.1016) (xy 0.2794 -0.1016) (xy 0.2794 0.9906) (xy -0.2794 0.9906)
			)
			(stroke
				(width 0)
				(type default)
			)
			(fill no)
			(layer "F.CrtYd")
		)
		(fp_line
			(start 0.2794 -0.1016)
			(end -0.2794 -0.1016)
			(stroke
				(width 0.1)
				(type default)
			)
			(layer "F.Fab")
		)
		(fp_line
			(start -0.2794 -0.1016)
			(end -0.2794 0.9906)
			(stroke
				(width 0.1)
				(type default)
			)
			(layer "F.Fab")
		)
		(fp_line
			(start 0.2794 0.9906)
			(end 0.2794 -0.1016)
			(stroke
				(width 0.1)
				(type default)
			)
			(layer "F.Fab")
		)
		(fp_line
			(start -0.2794 0.9906)
			(end 0.2794 0.9906)
			(stroke
				(width 0.1)
				(type default)
			)
			(layer "F.Fab")
		)
		(pad "1" smd rect
			(at 0 0 90)
			(size 0.508 0.508)
			(layers "F.Cu" "F.Mask" "F.Paste")
			(net "VR_PVDDQ_ABC_AIREF1")
		)
		(pad "2" smd rect
			(at 0 0.889 90)
			(size 0.508 0.508)
			(layers "F.Cu" "F.Mask" "F.Paste")
			(net "ISENSE_PVDDQ_ABC_PH1_IMON")
		)
		(zone
			(layer "F.Cu")
			(hatch none 0.5)
			(connect_pads
				(clearance 0)
			)
			(min_thickness 0.25)
			(keepout
				(tracks allowed)
				(vias not_allowed)
				(pads allowed)
				(copperpour not_allowed)
				(footprints allowed)
			)
			(placement
				(enabled no)
				(sheetname "")
			)
			(fill
				(thermal_gap 0.5)
				(thermal_bridge_width 0.5)
				(island_removal_mode 0)
			)
			(polygon
				(pts
					(xy 342.250776 -11.544046) (xy 342.250776 -12.052046) (xy 342.631776 -12.052046) (xy 342.631776 -11.544046)
				)
			)
		)
		(zone
			(layer "F.Cu")
			(hatch none 0.5)
			(connect_pads
				(clearance 0)
			)
			(min_thickness 0.25)
			(keepout
				(tracks not_allowed)
				(vias allowed)
				(pads allowed)
				(copperpour not_allowed)
				(footprints allowed)
			)
			(placement
				(enabled no)
				(sheetname "")
			)
			(fill
				(thermal_gap 0.5)
				(thermal_bridge_width 0.5)
				(island_removal_mode 0)
			)
			(polygon
				(pts
					(xy 342.631776 -11.544046) (xy 342.631776 -12.052046) (xy 342.250776 -12.052046) (xy 342.250776 -11.544046)
				)
			)
		)
	)
)
